(kicad_pcb
	(version 20240108)
	(generator "pcbnew")
	(generator_version "8.0")
	(general
		(thickness 1.586)
		(legacy_teardrops no)
	)
	(paper "A4")
	(title_block
		(title "GMSL Serializer")
		(date "2024-11-27")
		(rev "1.1.1")
		(company "Antmicro Ltd")
		(comment 1 "www.antmicro.com")
		(comment 9 "footprints 83-87 of 117")
	)
	(layers
		(0 "F.Cu" signal)
		(1 "In1.Cu" power)
		(2 "In2.Cu" power)
		(31 "B.Cu" signal)
		(32 "B.Adhes" user "B.Adhesive")
		(33 "F.Adhes" user "F.Adhesive")
		(34 "B.Paste" user)
		(35 "F.Paste" user)
		(36 "B.SilkS" user "B.Silkscreen")
		(37 "F.SilkS" user "F.Silkscreen")
		(38 "B.Mask" user)
		(39 "F.Mask" user)
		(40 "Dwgs.User" user "User.Drawings")
		(41 "Cmts.User" user "User.Comments")
		(42 "Eco1.User" user "User.Eco1")
		(43 "Eco2.User" user "User.Eco2")
		(44 "Edge.Cuts" user)
		(45 "Margin" user)
		(46 "B.CrtYd" user "B.Courtyard")
		(47 "F.CrtYd" user "F.Courtyard")
		(48 "B.Fab" user)
		(49 "F.Fab" user)
	)
	(footprint "antmicro-footprints:SOT-523"
		(layer "F.Cu")
		(at 151.17 113.3 90)
		(property "Reference" "Q1"
			(at -0.7 1.825 90)
			(layer "F.SilkS")
			(effects
				(font
					(size 0.7 0.7)
					(thickness 0.15)
				)
				(justify left bottom)
			)
		)
		(property "Value" "DMG1012T-7"
			(at 0.1 1.824 90)
			(layer "F.Fab")
			(effects
				(font
					(size 0.7 0.7)
					(thickness 0.15)
				)
				(justify left bottom)
			)
		)
		(property "Footprint" "antmicro-footprints:SOT-523"
			(at 0 0 90)
			(layer "F.Fab")
			(hide yes)
			(effects
				(font
					(size 1.27 1.27)
					(thickness 0.15)
				)
			)
		)
		(property "Datasheet" "https://www.diodes.com/assets/Datasheets/ds31783.pdf"
			(at 0 0 90)
			(layer "F.Fab")
			(hide yes)
			(effects
				(font
					(size 1.27 1.27)
					(thickness 0.15)
				)
			)
		)
		(property "Author" "Antmicro"
			(at 264.47 -37.87 0)
			(layer "F.Fab")
			(hide yes)
			(effects
				(font
					(size 1 1)
					(thickness 0.15)
				)
			)
		)
		(property "License" "Apache-2.0"
			(at 264.47 -37.87 0)
			(layer "F.Fab")
			(hide yes)
			(effects
				(font
					(size 1 1)
					(thickness 0.15)
				)
			)
		)
		(property "MPN" "DMG1012T-7"
			(at 264.47 -37.87 0)
			(layer "F.Fab")
			(hide yes)
			(effects
				(font
					(size 1 1)
					(thickness 0.15)
				)
			)
		)
		(property "Manufacturer" "Diodes Incorporated"
			(at 264.47 -37.87 0)
			(layer "F.Fab")
			(hide yes)
			(effects
				(font
					(size 1 1)
					(thickness 0.15)
				)
			)
		)
		(property "Public" ""
			(at 264.47 -37.87 0)
			(layer "F.Fab")
			(hide yes)
			(effects
				(font
					(size 1 1)
					(thickness 0.15)
				)
			)
		)
		(sheetname "Supply")
		(sheetfile "supply.kicad_sch")
		(attr smd exclude_from_bom)
		(fp_line
			(start -0.277 -0.551)
			(end -0.277 -0.75)
			(stroke
				(width 0.15)
				(type solid)
			)
			(layer "F.SilkS")
		)
		(fp_line
			(start -0.725 -0.551)
			(end -0.277 -0.551)
			(stroke
				(width 0.15)
				(type solid)
			)
			(layer "F.SilkS")
		)
		(fp_line
			(start -0.927 -0.351)
			(end -0.725 -0.551)
			(stroke
				(width 0.15)
				(type solid)
			)
			(layer "F.SilkS")
		)
		(fp_line
			(start -0.927 -0.051)
			(end -0.927 -0.351)
			(stroke
				(width 0.15)
				(type solid)
			)
			(layer "F.SilkS")
		)
		(fp_circle
			(center -0.9652 0.9652)
			(end -0.9152 0.9652)
			(stroke
				(width 0.15)
				(type solid)
			)
			(fill solid)
			(layer "F.SilkS")
		)
		(fp_line
			(start 1.1 -1.16)
			(end 1.1 1.15)
			(stroke
				(width 0.05)
				(type solid)
			)
			(layer "F.CrtYd")
		)
		(fp_line
			(start -1.12 -1.16)
			(end 1.1 -1.16)
			(stroke
				(width 0.05)
				(type solid)
			)
			(layer "F.CrtYd")
		)
		(fp_line
			(start -1.12 -1.16)
			(end -1.12 1.15)
			(stroke
				(width 0.05)
				(type solid)
			)
			(layer "F.CrtYd")
		)
		(fp_line
			(start -1.12 1.15)
			(end 1.1 1.15)
			(stroke
				(width 0.05)
				(type solid)
			)
			(layer "F.CrtYd")
		)
		(fp_line
			(start 0.8 -0.425)
			(end -0.652 -0.425)
			(stroke
				(width 0.15)
				(type solid)
			)
			(layer "F.Fab")
		)
		(fp_line
			(start 0.8 -0.425)
			(end 0.8 0.424)
			(stroke
				(width 0.15)
				(type solid)
			)
			(layer "F.Fab")
		)
		(fp_line
			(start -0.652 -0.425)
			(end -0.802 -0.276)
			(stroke
				(width 0.15)
				(type solid)
			)
			(layer "F.Fab")
		)
		(fp_line
			(start -0.802 -0.276)
			(end -0.802 0.424)
			(stroke
				(width 0.15)
				(type solid)
			)
			(layer "F.Fab")
		)
		(fp_line
			(start 0.8 0.424)
			(end -0.802 0.424)
			(stroke
				(width 0.15)
				(type solid)
			)
			(layer "F.Fab")
		)
		(fp_circle
			(center -0.9652 0.9652)
			(end -0.9144 0.9652)
			(stroke
				(width 0.15)
				(type solid)
			)
			(fill none)
			(layer "F.Fab")
		)
		(fp_text user "Author: Antmicro"
			(at -1.12 6.224 90)
			(layer "F.Fab")
			(hide yes)
			(effects
				(font
					(size 0.7 0.7)
					(thickness 0.15)
				)
				(justify left bottom)
			)
		)
		(fp_text user "${REFERENCE}"
			(at -1.12 3.824 90)
			(layer "F.Fab")
			(hide yes)
			(effects
				(font
					(size 0.7 0.7)
					(thickness 0.15)
				)
				(justify left bottom)
			)
		)
		(fp_text user "License: Apache-2.0"
			(at -1.12 5.024 90)
			(layer "F.Fab")
			(hide yes)
			(effects
				(font
					(size 0.7 0.7)
					(thickness 0.15)
				)
				(justify left bottom)
			)
		)
		(pad "1" smd rect
			(at -0.5 0.65 90)
			(size 0.4 0.51)
			(layers "F.Cu" "F.Paste" "F.Mask")
			(net 12 "+1V2")
			(pinfunction "G")
			(pintype "passive")
		)
		(pad "2" smd rect
			(at 0.498 0.65 90)
			(size 0.4 0.51)
			(layers "F.Cu" "F.Paste" "F.Mask")
			(net 1 "GND")
			(pinfunction "S")
			(pintype "passive")
		)
		(pad "3" smd rect
			(at 0 -0.652 90)
			(size 0.4 0.51)
			(layers "F.Cu" "F.Paste" "F.Mask")
			(net 70 "Net-(D6-C)")
			(pinfunction "D")
			(pintype "passive")
		)
	)
	(footprint "antmicro-footprints:R_0402_1005Metric"
		(layer "F.Cu")
		(at 150.16 111.355 180)
		(descr "Resistor SMD 0402")
		(tags "resistor SMD 0402")
		(property "Reference" "R22"
			(at -3.05 -0.37 0)
			(layer "F.SilkS")
			(effects
				(font
					(size 0.7 0.7)
					(thickness 0.15)
				)
				(justify right bottom)
			)
		)
		(property "Value" "R_10k_0402"
			(at -1.011843 1.772047 0)
			(layer "F.Fab")
			(effects
				(font
					(size 0.7 0.7)
					(thickness 0.15)
				)
				(justify right bottom)
			)
		)
		(property "Footprint" "antmicro-footprints:R_0402_1005Metric"
			(at 0 0 180)
			(layer "F.Fab")
			(hide yes)
			(effects
				(font
					(size 1.27 1.27)
					(thickness 0.15)
				)
			)
		)
		(property "Datasheet" "https://www.bourns.com/docs/product-datasheets/cr.pdf"
			(at 0 0 180)
			(layer "F.Fab")
			(hide yes)
			(effects
				(font
					(size 1.27 1.27)
					(thickness 0.15)
				)
			)
		)
		(property "Author" "Antmicro"
			(at 300.32 222.71 0)
			(layer "F.Fab")
			(hide yes)
			(effects
				(font
					(size 1 1)
					(thickness 0.15)
				)
			)
		)
		(property "License" "Apache-2.0"
			(at 300.32 222.71 0)
			(layer "F.Fab")
			(hide yes)
			(effects
				(font
					(size 1 1)
					(thickness 0.15)
				)
			)
		)
		(property "MPN" "CR0402-FX-1002GLF"
			(at 300.32 222.71 0)
			(layer "F.Fab")
			(hide yes)
			(effects
				(font
					(size 1 1)
					(thickness 0.15)
				)
			)
		)
		(property "Manufacturer" "Bourns"
			(at 300.32 222.71 0)
			(layer "F.Fab")
			(hide yes)
			(effects
				(font
					(size 1 1)
					(thickness 0.15)
				)
			)
		)
		(property "Tolerance" "1%"
			(at 300.32 222.71 0)
			(layer "F.Fab")
			(hide yes)
			(effects
				(font
					(size 1 1)
					(thickness 0.15)
				)
			)
		)
		(property "Val" "10k"
			(at 300.32 222.71 0)
			(layer "F.Fab")
			(hide yes)
			(effects
				(font
					(size 1 1)
					(thickness 0.15)
				)
			)
		)
		(sheetname "Serializer")
		(sheetfile "serializer.kicad_sch")
		(attr smd exclude_from_bom dnp)
		(fp_rect
			(start -0.925 -0.47)
			(end 0.925 0.47)
			(stroke
				(width 0.05)
				(type default)
			)
			(fill none)
			(layer "F.CrtYd")
		)
		(fp_rect
			(start -0.5 -0.25)
			(end 0.5 0.25)
			(stroke
				(width 0.15)
				(type solid)
			)
			(fill none)
			(layer "F.Fab")
		)
		(fp_text user "Author: Antmicro"
			(at -0.95 4.169 0)
			(layer "F.Fab")
			(hide yes)
			(effects
				(font
					(size 0.7 0.7)
					(thickness 0.15)
				)
				(justify right bottom)
			)
		)
		(fp_text user "License: Apache-2.0"
			(at -0.95 5.169 0)
			(layer "F.Fab")
			(hide yes)
			(effects
				(font
					(size 0.7 0.7)
					(thickness 0.15)
				)
				(justify right bottom)
			)
		)
		(fp_text user "${REFERENCE}"
			(at -0.95 3.168 0)
			(layer "F.Fab")
			(hide yes)
			(effects
				(font
					(size 0.7 0.7)
					(thickness 0.15)
				)
				(justify right bottom)
			)
		)
		(pad "1" smd roundrect
			(at -0.48 0 180)
			(size 0.59 0.64)
			(layers "F.Cu" "F.Paste" "F.Mask")
			(roundrect_rratio 0.25)
			(net 1 "GND")
			(pintype "passive")
		)
		(pad "2" smd roundrect
			(at 0.48 0 180)
			(size 0.59 0.64)
			(layers "F.Cu" "F.Paste" "F.Mask")
			(roundrect_rratio 0.25)
			(net 68 "/Serializer/CFG1")
			(pintype "passive")
		)
	)
	(footprint "antmicro-footprints:R_0402_1005Metric"
		(layer "F.Cu")
		(at 132.17 81.196 180)
		(descr "Resistor SMD 0402")
		(tags "resistor SMD 0402")
		(property "Reference" "R9"
			(at 0.39 -1.454 0)
			(layer "F.SilkS")
			(effects
				(font
					(size 0.7 0.7)
					(thickness 0.15)
				)
				(justify right bottom)
			)
		)
		(property "Value" "R_52k3_0402"
			(at -1.011843 1.772047 0)
			(layer "F.Fab")
			(effects
				(font
					(size 0.7 0.7)
					(thickness 0.15)
				)
				(justify right bottom)
			)
		)
		(property "Footprint" "antmicro-footprints:R_0402_1005Metric"
			(at 0 0 180)
			(layer "F.Fab")
			(hide yes)
			(effects
				(font
					(size 1.27 1.27)
					(thickness 0.15)
				)
			)
		)
		(property "Datasheet" "https://www.bourns.com/docs/product-datasheets/cr.pdf"
			(at 0 0 180)
			(layer "F.Fab")
			(hide yes)
			(effects
				(font
					(size 1.27 1.27)
					(thickness 0.15)
				)
			)
		)
		(property "Author" "Antmicro"
			(at 265 164.692 0)
			(layer "F.Fab")
			(hide yes)
			(effects
				(font
					(size 1 1)
					(thickness 0.15)
				)
			)
		)
		(property "License" "Apache-2.0"
			(at 265 164.692 0)
			(layer "F.Fab")
			(hide yes)
			(effects
				(font
					(size 1 1)
					(thickness 0.15)
				)
			)
		)
		(property "MPN" "CR0402-FX-5232GLF"
			(at 265 164.692 0)
			(layer "F.Fab")
			(hide yes)
			(effects
				(font
					(size 1 1)
					(thickness 0.15)
				)
			)
		)
		(property "Manufacturer" "Bourns"
			(at 265 164.692 0)
			(layer "F.Fab")
			(hide yes)
			(effects
				(font
					(size 1 1)
					(thickness 0.15)
				)
			)
		)
		(property "Tolerance" "1%"
			(at 265 164.692 0)
			(layer "F.Fab")
			(hide yes)
			(effects
				(font
					(size 1 1)
					(thickness 0.15)
				)
			)
		)
		(property "Val" "52k3"
			(at 265 164.692 0)
			(layer "F.Fab")
			(hide yes)
			(effects
				(font
					(size 1 1)
					(thickness 0.15)
				)
			)
		)
		(sheetname "Supply")
		(sheetfile "supply.kicad_sch")
		(attr smd)
		(fp_rect
			(start -0.925 -0.47)
			(end 0.925 0.47)
			(stroke
				(width 0.05)
				(type default)
			)
			(fill none)
			(layer "F.CrtYd")
		)
		(fp_rect
			(start -0.5 -0.25)
			(end 0.5 0.25)
			(stroke
				(width 0.15)
				(type solid)
			)
			(fill none)
			(layer "F.Fab")
		)
		(fp_text user "${REFERENCE}"
			(at -0.95 3.168 0)
			(layer "F.Fab")
			(hide yes)
			(effects
				(font
					(size 0.7 0.7)
					(thickness 0.15)
				)
				(justify right bottom)
			)
		)
		(fp_text user "Author: Antmicro"
			(at -0.95 4.169 0)
			(layer "F.Fab")
			(hide yes)
			(effects
				(font
					(size 0.7 0.7)
					(thickness 0.15)
				)
				(justify right bottom)
			)
		)
		(fp_text user "License: Apache-2.0"
			(at -0.95 5.169 0)
			(layer "F.Fab")
			(hide yes)
			(effects
				(font
					(size 0.7 0.7)
					(thickness 0.15)
				)
				(justify right bottom)
			)
		)
		(pad "1" smd roundrect
			(at -0.48 0 180)
			(size 0.59 0.64)
			(layers "F.Cu" "F.Paste" "F.Mask")
			(roundrect_rratio 0.25)
			(net 64 "/Supply/FB_5V")
			(pintype "passive")
		)
		(pad "2" smd roundrect
			(at 0.48 0 180)
			(size 0.59 0.64)
			(layers "F.Cu" "F.Paste" "F.Mask")
			(roundrect_rratio 0.25)
			(net 7 "/Supply/OUT_5V")
			(pintype "passive")
		)
	)
	(footprint "antmicro-footprints:R_0402_1005Metric"
		(layer "F.Cu")
		(at 148.15 110.28 180)
		(descr "Resistor SMD 0402")
		(tags "resistor SMD 0402")
		(property "Reference" "R18"
			(at 0.93 -0.4 0)
			(layer "F.SilkS")
			(effects
				(font
					(size 0.7 0.7)
					(thickness 0.15)
				)
				(justify right bottom)
			)
		)
		(property "Value" "R_80k6_0402"
			(at -1.011843 1.772047 0)
			(layer "F.Fab")
			(effects
				(font
					(size 0.7 0.7)
					(thickness 0.15)
				)
				(justify right bottom)
			)
		)
		(property "Footprint" "antmicro-footprints:R_0402_1005Metric"
			(at 0 0 180)
			(layer "F.Fab")
			(hide yes)
			(effects
				(font
					(size 1.27 1.27)
					(thickness 0.15)
				)
			)
		)
		(property "Datasheet" "https://www.bourns.com/docs/product-datasheets/cr.pdf"
			(at 0 0 180)
			(layer "F.Fab")
			(hide yes)
			(effects
				(font
					(size 1.27 1.27)
					(thickness 0.15)
				)
			)
		)
		(property "Author" "Antmicro"
			(at 296.3 220.56 0)
			(layer "F.Fab")
			(hide yes)
			(effects
				(font
					(size 1 1)
					(thickness 0.15)
				)
			)
		)
		(property "License" "Apache-2.0"
			(at 296.3 220.56 0)
			(layer "F.Fab")
			(hide yes)
			(effects
				(font
					(size 1 1)
					(thickness 0.15)
				)
			)
		)
		(property "MPN" "CR0402-FX-8062GLF"
			(at 296.3 220.56 0)
			(layer "F.Fab")
			(hide yes)
			(effects
				(font
					(size 1 1)
					(thickness 0.15)
				)
			)
		)
		(property "Manufacturer" "Bourns"
			(at 296.3 220.56 0)
			(layer "F.Fab")
			(hide yes)
			(effects
				(font
					(size 1 1)
					(thickness 0.15)
				)
			)
		)
		(property "Tolerance" "1%"
			(at 296.3 220.56 0)
			(layer "F.Fab")
			(hide yes)
			(effects
				(font
					(size 1 1)
					(thickness 0.15)
				)
			)
		)
		(property "Val" "80k6"
			(at 296.3 220.56 0)
			(layer "F.Fab")
			(hide yes)
			(effects
				(font
					(size 1 1)
					(thickness 0.15)
				)
			)
		)
		(sheetname "Serializer")
		(sheetfile "serializer.kicad_sch")
		(attr smd exclude_from_bom dnp)
		(fp_rect
			(start -0.925 -0.47)
			(end 0.925 0.47)
			(stroke
				(width 0.05)
				(type default)
			)
			(fill none)
			(layer "F.CrtYd")
		)
		(fp_rect
			(start -0.5 -0.25)
			(end 0.5 0.25)
			(stroke
				(width 0.15)
				(type solid)
			)
			(fill none)
			(layer "F.Fab")
		)
		(fp_text user "License: Apache-2.0"
			(at -0.95 5.169 0)
			(layer "F.Fab")
			(hide yes)
			(effects
				(font
					(size 0.7 0.7)
					(thickness 0.15)
				)
				(justify right bottom)
			)
		)
		(fp_text user "${REFERENCE}"
			(at -0.95 3.168 0)
			(layer "F.Fab")
			(hide yes)
			(effects
				(font
					(size 0.7 0.7)
					(thickness 0.15)
				)
				(justify right bottom)
			)
		)
		(fp_text user "Author: Antmicro"
			(at -0.95 4.169 0)
			(layer "F.Fab")
			(hide yes)
			(effects
				(font
					(size 0.7 0.7)
					(thickness 0.15)
				)
				(justify right bottom)
			)
		)
		(pad "1" smd roundrect
			(at -0.48 0 180)
			(size 0.59 0.64)
			(layers "F.Cu" "F.Paste" "F.Mask")
			(roundrect_rratio 0.25)
			(net 66 "/Serializer/CFG0")
			(pintype "passive")
		)
		(pad "2" smd roundrect
			(at 0.48 0 180)
			(size 0.59 0.64)
			(layers "F.Cu" "F.Paste" "F.Mask")
			(roundrect_rratio 0.25)
			(net 10 "+3V3")
			(pintype "passive")
		)
	)
	(footprint "antmicro-footprints:TP_SMD_1.5mm"
		(layer "F.Cu")
		(at 139.5 118 180)
		(property "Reference" "TP3"
			(at -1.6 1 0)
			(layer "F.SilkS")
			(hide yes)
			(effects
				(font
					(size 0.7 0.7)
					(thickness 0.15)
				)
				(justify right bottom)
			)
		)
		(property "Value" "TP_1.5mm_SMD"
			(at 0 1.7 0)
			(layer "F.Fab")
			(effects
				(font
					(size 0.7 0.7)
					(thickness 0.15)
				)
				(justify right bottom)
			)
		)
		(property "Footprint" "antmicro-footprints:TP_SMD_1.5mm"
			(at 0 0 180)
			(layer "F.Fab")
			(hide yes)
			(effects
				(font
					(size 1.27 1.27)
					(thickness 0.15)
				)
			)
		)
		(property "Author" "Antmicro"
			(at 279 236 0)
			(layer "F.Fab")
			(hide yes)
			(effects
				(font
					(size 1 1)
					(thickness 0.15)
				)
			)
		)
		(property "License" "Apache-2.0"
			(at 279 236 0)
			(layer "F.Fab")
			(hide yes)
			(effects
				(font
					(size 1 1)
					(thickness 0.15)
				)
			)
		)
		(property "MPN" ""
			(at 279 236 0)
			(layer "F.Fab")
			(hide yes)
			(effects
				(font
					(size 1 1)
					(thickness 0.15)
				)
			)
		)
		(property "Manufacturer" ""
			(at 279 236 0)
			(layer "F.Fab")
			(hide yes)
			(effects
				(font
					(size 1 1)
					(thickness 0.15)
				)
			)
		)
		(sheetname "GMSL Connector")
		(sheetfile "GMSL.kicad_sch")
		(attr exclude_from_pos_files exclude_from_bom)
		(fp_circle
			(center 0 0)
			(end 0.85 0)
			(stroke
				(width 0.05)
				(type default)
			)
			(fill none)
			(layer "F.CrtYd")
		)
		(fp_text user "License: Apache-2.0"
			(at -0.7 5.301 0)
			(layer "F.Fab")
			(hide yes)
			(effects
				(font
					(size 0.7 0.7)
					(thickness 0.15)
				)
				(justify right bottom)
			)
		)
		(fp_text user "Author: Antmicro"
			(at -0.7 4.101 0)
			(layer "F.Fab")
			(hide yes)
			(effects
				(font
					(size 0.7 0.7)
					(thickness 0.15)
				)
				(justify right bottom)
			)
		)
		(fp_text user "${REFERENCE}"
			(at -0.7 2.9 0)
			(layer "F.Fab")
			(hide yes)
			(effects
				(font
					(size 0.7 0.7)
					(thickness 0.15)
				)
				(justify right bottom)
			)
		)
		(pad "1" smd circle
			(at 0 0 90)
			(size 1.5 1.5)
			(layers "F.Cu" "F.Mask")
			(net 2 "+12V")
			(pinfunction "1")
			(pintype "passive")
		)
	)
)
